(kicad_pcb
	(version 20260206)
	(generator "pcbnew")
	(generator_version "10.0")
	(general
		(thickness 1.6)
		(legacy_teardrops no)
	)
	(paper "A4")
	(title_block
		(title "baseboard — 13948-1b.1110WZS1818.brd")
		(comment 1 "Honey Badger (Wiwynn) / footprint 852 of 2523 (SU2), pads 482-606 of 896")
	)
	(layers
		(0 "F.Cu" signal "TOP")
		(4 "In1.Cu" signal "L2GND")
		(6 "In2.Cu" signal "L3")
		(8 "In3.Cu" signal "L4VCC")
		(10 "In4.Cu" signal "L5VCC")
		(12 "In5.Cu" signal "L6")
		(14 "In6.Cu" signal "L7GND")
		(2 "B.Cu" signal "BOTTOM")
		(9 "F.Adhes" user "F.Adhesive")
		(11 "B.Adhes" user "B.Adhesive")
		(13 "F.Paste" user "Package Geometry/Pastemask Top")
		(15 "B.Paste" user "Package Geometry/Pastemask Bottom")
		(5 "F.SilkS" user "Ref Des/Silkscreen Top")
		(7 "B.SilkS" user "Ref Des/Silkscreen Bottom")
		(1 "F.Mask" user "Board Geometry/Soldermask Top")
		(3 "B.Mask" user "Board Geometry/Soldermask Bottom")
		(17 "Dwgs.User" user "User.Drawings")
		(19 "Cmts.User" user "User.Comments")
		(21 "Eco1.User" user "User.Eco1")
		(23 "Eco2.User" user "User.Eco2")
		(25 "Edge.Cuts" user "Board Geometry/Outline")
		(27 "Margin" user)
		(31 "F.CrtYd" user "Package Geometry/Place Bound Top")
		(29 "B.CrtYd" user "Package Geometry/Place Bound Bottom")
		(35 "F.Fab" user "Ref Des/Assembly Top")
		(33 "B.Fab" user "Ref Des/Assembly Bottom")
	)
	(footprint ""
		(layer "F.Cu")
		(at 102.350062 -44.99991)
		(property "Reference" "SU2"
			(at 0 0 0)
			(layer "F.SilkS")
			(hide yes)
			(effects
				(font
					(size 1.27 1.27)
				)
			)
		)
		(property "Value" "SAS3008C0-1-DB-500020657-1-GP"
			(at -20.374102 -5.0292 0)
			(unlocked yes)
			(layer "F.Fab")
			(hide yes)
			(effects
				(font
					(size 1.016 1.016)
					(thickness 0.1524)
				)
			)
		)
		(property "Device Type" "BGA896D25H78"
			(at -20.374102 -6.5532 0)
			(unlocked yes)
			(layer "F.Fab")
			(hide yes)
			(effects
				(font
					(size 1.016 1.016)
					(thickness 0.1524)
				)
			)
		)
		(duplicate_pad_numbers_are_jumpers no)
		(pad "G6" smd circle
			(at -7.599934 -6.800088)
			(size 0.3556 0.3556)
			(layers "F.Cu" "F.Mask" "F.Paste")
			(net "Net_1059")
		)
		(pad "G7" smd circle
			(at -6.800088 -6.800088)
			(size 0.3556 0.3556)
			(layers "F.Cu" "F.Mask" "F.Paste")
			(net "GND")
		)
		(pad "G8" smd circle
			(at -5.999988 -6.800088)
			(size 0.3556 0.3556)
			(layers "F.Cu" "F.Mask" "F.Paste")
			(net "GND")
		)
		(pad "G9" smd circle
			(at -5.199888 -6.800088)
			(size 0.3556 0.3556)
			(layers "F.Cu" "F.Mask" "F.Paste")
			(net "GND")
		)
		(pad "G10" smd circle
			(at -4.400042 -6.800088)
			(size 0.3556 0.3556)
			(layers "F.Cu" "F.Mask" "F.Paste")
			(net "GND")
		)
		(pad "G11" smd circle
			(at -3.599942 -6.800088)
			(size 0.3556 0.3556)
			(layers "F.Cu" "F.Mask" "F.Paste")
			(net "GND")
		)
		(pad "G12" smd circle
			(at -2.800096 -6.800088)
			(size 0.3556 0.3556)
			(layers "F.Cu" "F.Mask" "F.Paste")
			(net "GND")
		)
		(pad "G13" smd circle
			(at -1.999996 -6.800088)
			(size 0.3556 0.3556)
			(layers "F.Cu" "F.Mask" "F.Paste")
			(net "GND")
		)
		(pad "G14" smd circle
			(at -1.199896 -6.800088)
			(size 0.3556 0.3556)
			(layers "F.Cu" "F.Mask" "F.Paste")
			(net "GND")
		)
		(pad "G15" smd circle
			(at -0.40005 -6.800088)
			(size 0.3556 0.3556)
			(layers "F.Cu" "F.Mask" "F.Paste")
			(net "GND")
		)
		(pad "G16" smd circle
			(at 0.40005 -6.800088)
			(size 0.3556 0.3556)
			(layers "F.Cu" "F.Mask" "F.Paste")
			(net "GND")
		)
		(pad "G17" smd circle
			(at 1.199896 -6.800088)
			(size 0.3556 0.3556)
			(layers "F.Cu" "F.Mask" "F.Paste")
			(net "GND")
		)
		(pad "G18" smd circle
			(at 1.999996 -6.800088)
			(size 0.3556 0.3556)
			(layers "F.Cu" "F.Mask" "F.Paste")
			(net "GND")
		)
		(pad "G19" smd circle
			(at 2.800096 -6.800088)
			(size 0.3556 0.3556)
			(layers "F.Cu" "F.Mask" "F.Paste")
			(net "GND")
		)
		(pad "G20" smd circle
			(at 3.599942 -6.800088)
			(size 0.3556 0.3556)
			(layers "F.Cu" "F.Mask" "F.Paste")
			(net "GND")
		)
		(pad "G21" smd circle
			(at 4.400042 -6.800088)
			(size 0.3556 0.3556)
			(layers "F.Cu" "F.Mask" "F.Paste")
			(net "GND")
		)
		(pad "G22" smd circle
			(at 5.199888 -6.800088)
			(size 0.3556 0.3556)
			(layers "F.Cu" "F.Mask" "F.Paste")
			(net "GND")
		)
		(pad "G23" smd circle
			(at 5.999988 -6.800088)
			(size 0.3556 0.3556)
			(layers "F.Cu" "F.Mask" "F.Paste")
			(net "GND")
		)
		(pad "G24" smd circle
			(at 6.800088 -6.800088)
			(size 0.3556 0.3556)
			(layers "F.Cu" "F.Mask" "F.Paste")
			(net "GND")
		)
		(pad "G25" smd circle
			(at 7.599934 -6.800088)
			(size 0.3556 0.3556)
			(layers "F.Cu" "F.Mask" "F.Paste")
			(net "GND")
		)
		(pad "G26" smd circle
			(at 8.400034 -6.800088)
			(size 0.3556 0.3556)
			(layers "F.Cu" "F.Mask" "F.Paste")
			(net "GND")
		)
		(pad "G27" smd circle
			(at 9.19988 -6.800088)
			(size 0.3556 0.3556)
			(layers "F.Cu" "F.Mask" "F.Paste")
			(net "P1V8_C")
		)
		(pad "G28" smd circle
			(at 9.99998 -6.800088)
			(size 0.3556 0.3556)
			(layers "F.Cu" "F.Mask" "F.Paste")
			(net "XM_ADDR_15")
		)
		(pad "G29" smd circle
			(at 10.80008 -6.800088)
			(size 0.3556 0.3556)
			(layers "F.Cu" "F.Mask" "F.Paste")
			(net "XM_ADDR_21")
		)
		(pad "G30" smd circle
			(at 11.599926 -6.800088)
			(size 0.3556 0.3556)
			(layers "F.Cu" "F.Mask" "F.Paste")
			(net "XM_DATA_13")
		)
		(pad "H1" smd circle
			(at -11.599926 -5.999988)
			(size 0.3556 0.3556)
			(layers "F.Cu" "F.Mask" "F.Paste")
			(net "GND")
		)
		(pad "H2" smd circle
			(at -10.80008 -5.999988)
			(size 0.3556 0.3556)
			(layers "F.Cu" "F.Mask" "F.Paste")
			(net "Net_1060")
		)
		(pad "H3" smd circle
			(at -9.99998 -5.999988)
			(size 0.3556 0.3556)
			(layers "F.Cu" "F.Mask" "F.Paste")
			(net "Net_1061")
		)
		(pad "H4" smd circle
			(at -9.19988 -5.999988)
			(size 0.3556 0.3556)
			(layers "F.Cu" "F.Mask" "F.Paste")
			(net "P1V8_C")
		)
		(pad "H5" smd circle
			(at -8.400034 -5.999988)
			(size 0.3556 0.3556)
			(layers "F.Cu" "F.Mask" "F.Paste")
			(net "GND")
		)
		(pad "H6" smd circle
			(at -7.599934 -5.999988)
			(size 0.3556 0.3556)
			(layers "F.Cu" "F.Mask" "F.Paste")
			(net "Net_1062")
		)
		(pad "H7" smd circle
			(at -6.800088 -5.999988)
			(size 0.3556 0.3556)
			(layers "F.Cu" "F.Mask" "F.Paste")
			(net "GND")
		)
		(pad "H8" smd circle
			(at -5.999988 -5.999988)
			(size 0.3556 0.3556)
			(layers "F.Cu" "F.Mask" "F.Paste")
			(net "GND")
		)
		(pad "H9" smd circle
			(at -5.199888 -5.999988)
			(size 0.3556 0.3556)
			(layers "F.Cu" "F.Mask" "F.Paste")
			(net "GND")
		)
		(pad "H10" smd circle
			(at -4.400042 -5.999988)
			(size 0.3556 0.3556)
			(layers "F.Cu" "F.Mask" "F.Paste")
			(net "GND")
		)
		(pad "H11" smd circle
			(at -3.599942 -5.999988)
			(size 0.3556 0.3556)
			(layers "F.Cu" "F.Mask" "F.Paste")
			(net "GND")
		)
		(pad "H12" smd circle
			(at -2.800096 -5.999988)
			(size 0.3556 0.3556)
			(layers "F.Cu" "F.Mask" "F.Paste")
			(net "GND")
		)
		(pad "H13" smd circle
			(at -1.999996 -5.999988)
			(size 0.3556 0.3556)
			(layers "F.Cu" "F.Mask" "F.Paste")
			(net "GND")
		)
		(pad "H14" smd circle
			(at -1.199896 -5.999988)
			(size 0.3556 0.3556)
			(layers "F.Cu" "F.Mask" "F.Paste")
			(net "GND")
		)
		(pad "H15" smd circle
			(at -0.40005 -5.999988)
			(size 0.3556 0.3556)
			(layers "F.Cu" "F.Mask" "F.Paste")
			(net "GND")
		)
		(pad "H16" smd circle
			(at 0.40005 -5.999988)
			(size 0.3556 0.3556)
			(layers "F.Cu" "F.Mask" "F.Paste")
			(net "GND")
		)
		(pad "H17" smd circle
			(at 1.199896 -5.999988)
			(size 0.3556 0.3556)
			(layers "F.Cu" "F.Mask" "F.Paste")
			(net "GND")
		)
		(pad "H18" smd circle
			(at 1.999996 -5.999988)
			(size 0.3556 0.3556)
			(layers "F.Cu" "F.Mask" "F.Paste")
			(net "GND")
		)
		(pad "H19" smd circle
			(at 2.800096 -5.999988)
			(size 0.3556 0.3556)
			(layers "F.Cu" "F.Mask" "F.Paste")
			(net "GND")
		)
		(pad "H20" smd circle
			(at 3.599942 -5.999988)
			(size 0.3556 0.3556)
			(layers "F.Cu" "F.Mask" "F.Paste")
			(net "GND")
		)
		(pad "H21" smd circle
			(at 4.400042 -5.999988)
			(size 0.3556 0.3556)
			(layers "F.Cu" "F.Mask" "F.Paste")
			(net "GND")
		)
		(pad "H22" smd circle
			(at 5.199888 -5.999988)
			(size 0.3556 0.3556)
			(layers "F.Cu" "F.Mask" "F.Paste")
			(net "GND")
		)
		(pad "H23" smd circle
			(at 5.999988 -5.999988)
			(size 0.3556 0.3556)
			(layers "F.Cu" "F.Mask" "F.Paste")
			(net "GND")
		)
		(pad "H24" smd circle
			(at 6.800088 -5.999988)
			(size 0.3556 0.3556)
			(layers "F.Cu" "F.Mask" "F.Paste")
			(net "GND")
		)
		(pad "H25" smd circle
			(at 7.599934 -5.999988)
			(size 0.3556 0.3556)
			(layers "F.Cu" "F.Mask" "F.Paste")
			(net "GND")
		)
		(pad "H26" smd circle
			(at 8.400034 -5.999988)
			(size 0.3556 0.3556)
			(layers "F.Cu" "F.Mask" "F.Paste")
			(net "P1V8_C")
		)
		(pad "H27" smd circle
			(at 9.19988 -5.999988)
			(size 0.3556 0.3556)
			(layers "F.Cu" "F.Mask" "F.Paste")
			(net "GND")
		)
		(pad "H28" smd circle
			(at 9.99998 -5.999988)
			(size 0.3556 0.3556)
			(layers "F.Cu" "F.Mask" "F.Paste")
			(net "XM_DATA_0")
		)
		(pad "H29" smd circle
			(at 10.80008 -5.999988)
			(size 0.3556 0.3556)
			(layers "F.Cu" "F.Mask" "F.Paste")
			(net "XM_ADDR_25")
		)
		(pad "H30" smd circle
			(at 11.599926 -5.999988)
			(size 0.3556 0.3556)
			(layers "F.Cu" "F.Mask" "F.Paste")
			(net "XM_ADDR_18")
		)
		(pad "J1" smd circle
			(at -11.599926 -5.199888)
			(size 0.3556 0.3556)
			(layers "F.Cu" "F.Mask" "F.Paste")
			(net "Net_1077")
		)
		(pad "J2" smd circle
			(at -10.80008 -5.199888)
			(size 0.3556 0.3556)
			(layers "F.Cu" "F.Mask" "F.Paste")
			(net "Net_1063")
		)
		(pad "J3" smd circle
			(at -9.99998 -5.199888)
			(size 0.3556 0.3556)
			(layers "F.Cu" "F.Mask" "F.Paste")
			(net "Net_1064")
		)
		(pad "J4" smd circle
			(at -9.19988 -5.199888)
			(size 0.3556 0.3556)
			(layers "F.Cu" "F.Mask" "F.Paste")
			(net "GND")
		)
		(pad "J5" smd circle
			(at -8.400034 -5.199888)
			(size 0.3556 0.3556)
			(layers "F.Cu" "F.Mask" "F.Paste")
			(net "P1V8_C")
		)
		(pad "J6" smd circle
			(at -7.599934 -5.199888)
			(size 0.3556 0.3556)
			(layers "F.Cu" "F.Mask" "F.Paste")
			(net "Net_1065")
		)
		(pad "J7" smd circle
			(at -6.800088 -5.199888)
			(size 0.3556 0.3556)
			(layers "F.Cu" "F.Mask" "F.Paste")
			(net "GND")
		)
		(pad "J8" smd circle
			(at -5.999988 -5.199888)
			(size 0.3556 0.3556)
			(layers "F.Cu" "F.Mask" "F.Paste")
			(net "GND")
		)
		(pad "J9" smd circle
			(at -5.199888 -5.199888)
			(size 0.3556 0.3556)
			(layers "F.Cu" "F.Mask" "F.Paste")
			(net "GND")
		)
		(pad "J10" smd circle
			(at -4.400042 -5.199888)
			(size 0.3556 0.3556)
			(layers "F.Cu" "F.Mask" "F.Paste")
			(net "GND")
		)
		(pad "J11" smd circle
			(at -3.599942 -5.199888)
			(size 0.3556 0.3556)
			(layers "F.Cu" "F.Mask" "F.Paste")
			(net "GND")
		)
		(pad "J12" smd circle
			(at -2.800096 -5.199888)
			(size 0.3556 0.3556)
			(layers "F.Cu" "F.Mask" "F.Paste")
			(net "P0V955_C")
		)
		(pad "J13" smd circle
			(at -1.999996 -5.199888)
			(size 0.3556 0.3556)
			(layers "F.Cu" "F.Mask" "F.Paste")
			(net "GND")
		)
		(pad "J14" smd circle
			(at -1.199896 -5.199888)
			(size 0.3556 0.3556)
			(layers "F.Cu" "F.Mask" "F.Paste")
			(net "GND")
		)
		(pad "J15" smd circle
			(at -0.40005 -5.199888)
			(size 0.3556 0.3556)
			(layers "F.Cu" "F.Mask" "F.Paste")
			(net "GND")
		)
		(pad "J16" smd circle
			(at 0.40005 -5.199888)
			(size 0.3556 0.3556)
			(layers "F.Cu" "F.Mask" "F.Paste")
			(net "GND")
		)
		(pad "J17" smd circle
			(at 1.199896 -5.199888)
			(size 0.3556 0.3556)
			(layers "F.Cu" "F.Mask" "F.Paste")
			(net "GND")
		)
		(pad "J18" smd circle
			(at 1.999996 -5.199888)
			(size 0.3556 0.3556)
			(layers "F.Cu" "F.Mask" "F.Paste")
			(net "GND")
		)
		(pad "J19" smd circle
			(at 2.800096 -5.199888)
			(size 0.3556 0.3556)
			(layers "F.Cu" "F.Mask" "F.Paste")
			(net "GND")
		)
		(pad "J20" smd circle
			(at 3.599942 -5.199888)
			(size 0.3556 0.3556)
			(layers "F.Cu" "F.Mask" "F.Paste")
			(net "GND")
		)
		(pad "J21" smd circle
			(at 4.400042 -5.199888)
			(size 0.3556 0.3556)
			(layers "F.Cu" "F.Mask" "F.Paste")
			(net "GND")
		)
		(pad "J22" smd circle
			(at 5.199888 -5.199888)
			(size 0.3556 0.3556)
			(layers "F.Cu" "F.Mask" "F.Paste")
			(net "GND")
		)
		(pad "J23" smd circle
			(at 5.999988 -5.199888)
			(size 0.3556 0.3556)
			(layers "F.Cu" "F.Mask" "F.Paste")
			(net "GND")
		)
		(pad "J24" smd circle
			(at 6.800088 -5.199888)
			(size 0.3556 0.3556)
			(layers "F.Cu" "F.Mask" "F.Paste")
			(net "GND")
		)
		(pad "J25" smd circle
			(at 7.599934 -5.199888)
			(size 0.3556 0.3556)
			(layers "F.Cu" "F.Mask" "F.Paste")
			(net "GND")
		)
		(pad "J26" smd circle
			(at 8.400034 -5.199888)
			(size 0.3556 0.3556)
			(layers "F.Cu" "F.Mask" "F.Paste")
			(net "GND")
		)
		(pad "J27" smd circle
			(at 9.19988 -5.199888)
			(size 0.3556 0.3556)
			(layers "F.Cu" "F.Mask" "F.Paste")
			(net "P1V8_C")
		)
		(pad "J28" smd circle
			(at 9.99998 -5.199888)
			(size 0.3556 0.3556)
			(layers "F.Cu" "F.Mask" "F.Paste")
			(net "XM_DATA_12")
		)
		(pad "J29" smd circle
			(at 10.80008 -5.199888)
			(size 0.3556 0.3556)
			(layers "F.Cu" "F.Mask" "F.Paste")
			(net "XM_ADDR_22")
		)
		(pad "J30" smd circle
			(at 11.599926 -5.199888)
			(size 0.3556 0.3556)
			(layers "F.Cu" "F.Mask" "F.Paste")
			(net "XM_ADDR_24")
		)
		(pad "K1" smd circle
			(at -11.599926 -4.400042)
			(size 0.3556 0.3556)
			(layers "F.Cu" "F.Mask" "F.Paste")
			(net "SIO_LOAD_1")
		)
		(pad "K2" smd circle
			(at -10.80008 -4.400042)
			(size 0.3556 0.3556)
			(layers "F.Cu" "F.Mask" "F.Paste")
			(net "SIO_DOUT_0")
		)
		(pad "K3" smd circle
			(at -9.99998 -4.400042)
			(size 0.3556 0.3556)
			(layers "F.Cu" "F.Mask" "F.Paste")
			(net "GND")
		)
		(pad "K4" smd circle
			(at -9.19988 -4.400042)
			(size 0.3556 0.3556)
			(layers "F.Cu" "F.Mask" "F.Paste")
			(net "P1V8_C")
		)
		(pad "K5" smd circle
			(at -8.400034 -4.400042)
			(size 0.3556 0.3556)
			(layers "F.Cu" "F.Mask" "F.Paste")
			(net "GND")
		)
		(pad "K6" smd circle
			(at -7.599934 -4.400042)
			(size 0.3556 0.3556)
			(layers "F.Cu" "F.Mask" "F.Paste")
			(net "Net_1066")
		)
		(pad "K7" smd circle
			(at -6.800088 -4.400042)
			(size 0.3556 0.3556)
			(layers "F.Cu" "F.Mask" "F.Paste")
			(net "GND")
		)
		(pad "K8" smd circle
			(at -5.999988 -4.400042)
			(size 0.3556 0.3556)
			(layers "F.Cu" "F.Mask" "F.Paste")
			(net "GND")
		)
		(pad "K9" smd circle
			(at -5.199888 -4.400042)
			(size 0.3556 0.3556)
			(layers "F.Cu" "F.Mask" "F.Paste")
			(net "GND")
		)
		(pad "K10" smd circle
			(at -4.400042 -4.400042)
			(size 0.3556 0.3556)
			(layers "F.Cu" "F.Mask" "F.Paste")
			(net "GND")
		)
		(pad "K11" smd circle
			(at -3.599942 -4.400042)
			(size 0.3556 0.3556)
			(layers "F.Cu" "F.Mask" "F.Paste")
			(net "GND")
		)
		(pad "K12" smd circle
			(at -2.800096 -4.400042)
			(size 0.3556 0.3556)
			(layers "F.Cu" "F.Mask" "F.Paste")
			(net "GND")
		)
		(pad "K13" smd circle
			(at -1.999996 -4.400042)
			(size 0.3556 0.3556)
			(layers "F.Cu" "F.Mask" "F.Paste")
			(net "P0V955_C")
		)
		(pad "K14" smd circle
			(at -1.199896 -4.400042)
			(size 0.3556 0.3556)
			(layers "F.Cu" "F.Mask" "F.Paste")
			(net "GND")
		)
		(pad "K15" smd circle
			(at -0.40005 -4.400042)
			(size 0.3556 0.3556)
			(layers "F.Cu" "F.Mask" "F.Paste")
			(net "GND")
		)
		(pad "K16" smd circle
			(at 0.40005 -4.400042)
			(size 0.3556 0.3556)
			(layers "F.Cu" "F.Mask" "F.Paste")
			(net "GND")
		)
		(pad "K17" smd circle
			(at 1.199896 -4.400042)
			(size 0.3556 0.3556)
			(layers "F.Cu" "F.Mask" "F.Paste")
			(net "GND")
		)
		(pad "K18" smd circle
			(at 1.999996 -4.400042)
			(size 0.3556 0.3556)
			(layers "F.Cu" "F.Mask" "F.Paste")
			(net "GND")
		)
		(pad "K19" smd circle
			(at 2.800096 -4.400042)
			(size 0.3556 0.3556)
			(layers "F.Cu" "F.Mask" "F.Paste")
			(net "GND")
		)
		(pad "K20" smd circle
			(at 3.599942 -4.400042)
			(size 0.3556 0.3556)
			(layers "F.Cu" "F.Mask" "F.Paste")
			(net "GND")
		)
		(pad "K21" smd circle
			(at 4.400042 -4.400042)
			(size 0.3556 0.3556)
			(layers "F.Cu" "F.Mask" "F.Paste")
			(net "P0V955_C")
		)
		(pad "K22" smd circle
			(at 5.199888 -4.400042)
			(size 0.3556 0.3556)
			(layers "F.Cu" "F.Mask" "F.Paste")
			(net "GND")
		)
		(pad "K23" smd circle
			(at 5.999988 -4.400042)
			(size 0.3556 0.3556)
			(layers "F.Cu" "F.Mask" "F.Paste")
			(net "GND")
		)
		(pad "K24" smd circle
			(at 6.800088 -4.400042)
			(size 0.3556 0.3556)
			(layers "F.Cu" "F.Mask" "F.Paste")
			(net "GND")
		)
		(pad "K25" smd circle
			(at 7.599934 -4.400042)
			(size 0.3556 0.3556)
			(layers "F.Cu" "F.Mask" "F.Paste")
			(net "GND")
		)
		(pad "K26" smd circle
			(at 8.400034 -4.400042)
			(size 0.3556 0.3556)
			(layers "F.Cu" "F.Mask" "F.Paste")
			(net "P1V8_C")
		)
		(pad "K27" smd circle
			(at 9.19988 -4.400042)
			(size 0.3556 0.3556)
			(layers "F.Cu" "F.Mask" "F.Paste")
			(net "GND")
		)
		(pad "K28" smd circle
			(at 9.99998 -4.400042)
			(size 0.3556 0.3556)
			(layers "F.Cu" "F.Mask" "F.Paste")
			(net "XM_DATA_2")
		)
		(pad "K29" smd circle
			(at 10.80008 -4.400042)
			(size 0.3556 0.3556)
			(layers "F.Cu" "F.Mask" "F.Paste")
			(net "XM_ADDR_23")
		)
		(pad "K30" smd circle
			(at 11.599926 -4.400042)
			(size 0.3556 0.3556)
			(layers "F.Cu" "F.Mask" "F.Paste")
			(net "XM_DATA_1")
		)
		(pad "L1" smd circle
			(at -11.599926 -3.599942)
			(size 0.3556 0.3556)
			(layers "F.Cu" "F.Mask" "F.Paste")
			(net "SIO_CLK_1")
		)
		(pad "L2" smd circle
			(at -10.80008 -3.599942)
			(size 0.3556 0.3556)
			(layers "F.Cu" "F.Mask" "F.Paste")
			(net "SIO_DIN_1")
		)
		(pad "L3" smd circle
			(at -9.99998 -3.599942)
			(size 0.3556 0.3556)
			(layers "F.Cu" "F.Mask" "F.Paste")
			(net "Net_1067")
		)
		(pad "L4" smd circle
			(at -9.19988 -3.599942)
			(size 0.3556 0.3556)
			(layers "F.Cu" "F.Mask" "F.Paste")
			(net "GND")
		)
		(pad "L5" smd circle
			(at -8.400034 -3.599942)
			(size 0.3556 0.3556)
			(layers "F.Cu" "F.Mask" "F.Paste")
			(net "P1V8_C")
		)
		(pad "L6" smd circle
			(at -7.599934 -3.599942)
			(size 0.3556 0.3556)
			(layers "F.Cu" "F.Mask" "F.Paste")
			(net "ICE1_TDI")
		)
		(pad "L7" smd circle
			(at -6.800088 -3.599942)
			(size 0.3556 0.3556)
			(layers "F.Cu" "F.Mask" "F.Paste")
			(net "GND")
		)
		(pad "L8" smd circle
			(at -5.999988 -3.599942)
			(size 0.3556 0.3556)
			(layers "F.Cu" "F.Mask" "F.Paste")
			(net "GND")
		)
		(pad "L9" smd circle
			(at -5.199888 -3.599942)
			(size 0.3556 0.3556)
			(layers "F.Cu" "F.Mask" "F.Paste")
			(net "GND")
		)
		(pad "L10" smd circle
			(at -4.400042 -3.599942)
			(size 0.3556 0.3556)
			(layers "F.Cu" "F.Mask" "F.Paste")
			(net "GND")
		)
	)
)
